(kicad_pcb
	(version 20260206)
	(generator "pcbnew")
	(generator_version "10.0")
	(general
		(thickness 1.6)
		(legacy_teardrops no)
	)
	(paper "A4")
	(title_block
		(title "03242023_DA0F0TMBIJ0_F0T_Motherboard_J_brd_V01_OCP.brd")
		(comment 1 "Grand Teton / footprint 885 of 6105 (J5), pads 1-112 of 291")
	)
	(layers
		(0 "F.Cu" signal "TOP")
		(4 "In1.Cu" signal "GND")
		(6 "In2.Cu" signal "IN1")
		(8 "In3.Cu" signal "GND1")
		(10 "In4.Cu" signal "IN2")
		(12 "In5.Cu" signal "GND2")
		(14 "In6.Cu" signal "IN3")
		(16 "In7.Cu" signal "GND3")
		(18 "In8.Cu" signal "VCC")
		(20 "In9.Cu" signal "VCC1")
		(22 "In10.Cu" signal "GND4")
		(24 "In11.Cu" signal "IN4")
		(26 "In12.Cu" signal "GND5")
		(28 "In13.Cu" signal "IN5")
		(30 "In14.Cu" signal "GND6")
		(32 "In15.Cu" signal "IN6")
		(34 "In16.Cu" signal "GND7")
		(2 "B.Cu" signal "BOTTOM")
		(9 "F.Adhes" user "F.Adhesive")
		(11 "B.Adhes" user "B.Adhesive")
		(13 "F.Paste" user "Package Geometry/Pastemask Top")
		(15 "B.Paste" user "Package Geometry/Pastemask Bottom")
		(5 "F.SilkS" user "Ref Des/Silkscreen Top")
		(7 "B.SilkS" user "Ref Des/Silkscreen Bottom")
		(1 "F.Mask" user "Board Geometry/Soldermask Top")
		(3 "B.Mask" user "Board Geometry/Soldermask Bottom")
		(17 "Dwgs.User" user "User.Drawings")
		(19 "Cmts.User" user "User.Comments")
		(21 "Eco1.User" user "User.Eco1")
		(23 "Eco2.User" user "User.Eco2")
		(25 "Edge.Cuts" user "Board Geometry/Outline")
		(27 "Margin" user)
		(31 "F.CrtYd" user "Package Geometry/Place Bound Top")
		(29 "B.CrtYd" user "Package Geometry/Place Bound Bottom")
		(35 "F.Fab" user "Ref Des/Assembly Top")
		(33 "B.Fab" user "Ref Des/Assembly Bottom")
	)
	(footprint ""
		(layer "F.Cu")
		(at 273.218148 -258.091686)
		(property "Reference" "J5"
			(at -3.683 -81.702148 0)
			(unlocked yes)
			(layer "F.SilkS")
			(effects
				(font
					(size 0.7874 0.5842)
					(thickness 0.1524)
				)
				(justify left)
			)
		)
		(property "Value" ""
			(at 0 0 0)
			(layer "F.Fab")
			(effects
				(font
					(size 1.27 1.27)
				)
			)
		)
		(duplicate_pad_numbers_are_jumpers no)
		(pad "1" smd rect
			(at -2.050034 -63.324994 270)
			(size 0.519938 1.4986)
			(layers "F.Cu" "F.Mask" "F.Paste")
			(net "P12V_S3_AUX_CPU0_NVDIMM")
		)
		(pad "2" smd rect
			(at -2.050034 -62.47511 270)
			(size 0.519938 1.4986)
			(layers "F.Cu" "F.Mask" "F.Paste")
			(net "TP_CHC_CPU0_DIMM1_FRU_0")
		)
		(pad "3" smd rect
			(at -2.050034 -61.624972 270)
			(size 0.519938 1.4986)
			(layers "F.Cu" "F.Mask" "F.Paste")
			(net "P3V3_AUX")
		)
		(pad "4" smd rect
			(at -2.050034 -60.775088 270)
			(size 0.519938 1.4986)
			(layers "F.Cu" "F.Mask" "F.Paste")
			(net "I3C_SPD_DDRABCD_CPU0_LVC1_SCL_4")
		)
		(pad "5" smd rect
			(at -2.050034 -59.92495 270)
			(size 0.519938 1.4986)
			(layers "F.Cu" "F.Mask" "F.Paste")
			(net "I3C_SPD_DDRABCD_CPU0_LVC1_SDA")
		)
		(pad "6" smd rect
			(at -2.050034 -59.075066 270)
			(size 0.519938 1.4986)
			(layers "F.Cu" "F.Mask" "F.Paste")
			(net "GND")
		)
		(pad "7" smd rect
			(at -2.050034 -58.224928 270)
			(size 0.519938 1.4986)
			(layers "F.Cu" "F.Mask" "F.Paste")
			(net "M_C_CPU0_SA_DQ<0>")
		)
		(pad "8" smd rect
			(at -2.050034 -57.375044 270)
			(size 0.519938 1.4986)
			(layers "F.Cu" "F.Mask" "F.Paste")
			(net "GND")
		)
		(pad "9" smd rect
			(at -2.050034 -56.524906 270)
			(size 0.519938 1.4986)
			(layers "F.Cu" "F.Mask" "F.Paste")
			(net "M_C_CPU0_SA_DQ<1>")
		)
		(pad "10" smd rect
			(at -2.050034 -55.675022 270)
			(size 0.519938 1.4986)
			(layers "F.Cu" "F.Mask" "F.Paste")
			(net "GND")
		)
		(pad "11" smd rect
			(at -2.050034 -54.824884 270)
			(size 0.519938 1.4986)
			(layers "F.Cu" "F.Mask" "F.Paste")
			(net "M_C_CPU0_SA_DQS_DP<0>")
		)
		(pad "12" smd rect
			(at -2.050034 -53.975 270)
			(size 0.519938 1.4986)
			(layers "F.Cu" "F.Mask" "F.Paste")
			(net "M_C_CPU0_SA_DQS_DN<0>")
		)
		(pad "13" smd rect
			(at -2.050034 -53.125116 270)
			(size 0.519938 1.4986)
			(layers "F.Cu" "F.Mask" "F.Paste")
			(net "GND")
		)
		(pad "14" smd rect
			(at -2.050034 -52.274978 270)
			(size 0.519938 1.4986)
			(layers "F.Cu" "F.Mask" "F.Paste")
			(net "M_C_CPU0_SA_DQ<4>")
		)
		(pad "15" smd rect
			(at -2.050034 -51.425094 270)
			(size 0.519938 1.4986)
			(layers "F.Cu" "F.Mask" "F.Paste")
			(net "GND")
		)
		(pad "16" smd rect
			(at -2.050034 -50.574956 270)
			(size 0.519938 1.4986)
			(layers "F.Cu" "F.Mask" "F.Paste")
			(net "M_C_CPU0_SA_DQ<5>")
		)
		(pad "17" smd rect
			(at -2.050034 -49.725072 270)
			(size 0.519938 1.4986)
			(layers "F.Cu" "F.Mask" "F.Paste")
			(net "GND")
		)
		(pad "18" smd rect
			(at -2.050034 -48.874934 270)
			(size 0.519938 1.4986)
			(layers "F.Cu" "F.Mask" "F.Paste")
			(net "M_C_CPU0_SA_DQ<8>")
		)
		(pad "19" smd rect
			(at -2.050034 -48.02505 270)
			(size 0.519938 1.4986)
			(layers "F.Cu" "F.Mask" "F.Paste")
			(net "GND")
		)
		(pad "20" smd rect
			(at -2.050034 -47.174912 270)
			(size 0.519938 1.4986)
			(layers "F.Cu" "F.Mask" "F.Paste")
			(net "M_C_CPU0_SA_DQ<9>")
		)
		(pad "21" smd rect
			(at -2.050034 -46.325028 270)
			(size 0.519938 1.4986)
			(layers "F.Cu" "F.Mask" "F.Paste")
			(net "GND")
		)
		(pad "22" smd rect
			(at -2.050034 -45.47489 270)
			(size 0.519938 1.4986)
			(layers "F.Cu" "F.Mask" "F.Paste")
			(net "M_C_CPU0_SA_DQS_DP<1>")
		)
		(pad "23" smd rect
			(at -2.050034 -44.625006 270)
			(size 0.519938 1.4986)
			(layers "F.Cu" "F.Mask" "F.Paste")
			(net "M_C_CPU0_SA_DQS_DN<1>")
		)
		(pad "24" smd rect
			(at -2.050034 -43.775122 270)
			(size 0.519938 1.4986)
			(layers "F.Cu" "F.Mask" "F.Paste")
			(net "GND")
		)
		(pad "25" smd rect
			(at -2.050034 -42.924984 270)
			(size 0.519938 1.4986)
			(layers "F.Cu" "F.Mask" "F.Paste")
			(net "M_C_CPU0_SA_DQ<12>")
		)
		(pad "26" smd rect
			(at -2.050034 -42.0751 270)
			(size 0.519938 1.4986)
			(layers "F.Cu" "F.Mask" "F.Paste")
			(net "GND")
		)
		(pad "27" smd rect
			(at -2.050034 -41.224962 270)
			(size 0.519938 1.4986)
			(layers "F.Cu" "F.Mask" "F.Paste")
			(net "M_C_CPU0_SA_DQ<13>")
		)
		(pad "28" smd rect
			(at -2.050034 -40.375078 270)
			(size 0.519938 1.4986)
			(layers "F.Cu" "F.Mask" "F.Paste")
			(net "GND")
		)
		(pad "29" smd rect
			(at -2.050034 -39.52494 270)
			(size 0.519938 1.4986)
			(layers "F.Cu" "F.Mask" "F.Paste")
			(net "M_C_CPU0_SA_DQ<16>")
		)
		(pad "30" smd rect
			(at -2.050034 -38.675056 270)
			(size 0.519938 1.4986)
			(layers "F.Cu" "F.Mask" "F.Paste")
			(net "GND")
		)
		(pad "31" smd rect
			(at -2.050034 -37.824918 270)
			(size 0.519938 1.4986)
			(layers "F.Cu" "F.Mask" "F.Paste")
			(net "M_C_CPU0_SA_DQ<17>")
		)
		(pad "32" smd rect
			(at -2.050034 -36.975034 270)
			(size 0.519938 1.4986)
			(layers "F.Cu" "F.Mask" "F.Paste")
			(net "GND")
		)
		(pad "33" smd rect
			(at -2.050034 -36.124896 270)
			(size 0.519938 1.4986)
			(layers "F.Cu" "F.Mask" "F.Paste")
			(net "M_C_CPU0_SA_DQS_DP<2>")
		)
		(pad "34" smd rect
			(at -2.050034 -35.275012 270)
			(size 0.519938 1.4986)
			(layers "F.Cu" "F.Mask" "F.Paste")
			(net "M_C_CPU0_SA_DQS_DN<2>")
		)
		(pad "35" smd rect
			(at -2.050034 -34.425128 270)
			(size 0.519938 1.4986)
			(layers "F.Cu" "F.Mask" "F.Paste")
			(net "GND")
		)
		(pad "36" smd rect
			(at -2.050034 -33.57499 270)
			(size 0.519938 1.4986)
			(layers "F.Cu" "F.Mask" "F.Paste")
			(net "M_C_CPU0_SA_DQ<20>")
		)
		(pad "37" smd rect
			(at -2.050034 -32.725106 270)
			(size 0.519938 1.4986)
			(layers "F.Cu" "F.Mask" "F.Paste")
			(net "GND")
		)
		(pad "38" smd rect
			(at -2.050034 -31.874968 270)
			(size 0.519938 1.4986)
			(layers "F.Cu" "F.Mask" "F.Paste")
			(net "M_C_CPU0_SA_DQ<21>")
		)
		(pad "39" smd rect
			(at -2.050034 -31.025084 270)
			(size 0.519938 1.4986)
			(layers "F.Cu" "F.Mask" "F.Paste")
			(net "GND")
		)
		(pad "40" smd rect
			(at -2.050034 -30.174946 270)
			(size 0.519938 1.4986)
			(layers "F.Cu" "F.Mask" "F.Paste")
			(net "M_C_CPU0_SA_DQ<24>")
		)
		(pad "41" smd rect
			(at -2.050034 -29.325062 270)
			(size 0.519938 1.4986)
			(layers "F.Cu" "F.Mask" "F.Paste")
			(net "GND")
		)
		(pad "42" smd rect
			(at -2.050034 -28.474924 270)
			(size 0.519938 1.4986)
			(layers "F.Cu" "F.Mask" "F.Paste")
			(net "M_C_CPU0_SA_DQ<25>")
		)
		(pad "43" smd rect
			(at -2.050034 -27.62504 270)
			(size 0.519938 1.4986)
			(layers "F.Cu" "F.Mask" "F.Paste")
			(net "GND")
		)
		(pad "44" smd rect
			(at -2.050034 -26.774902 270)
			(size 0.519938 1.4986)
			(layers "F.Cu" "F.Mask" "F.Paste")
			(net "M_C_CPU0_SA_DQS_DP<3>")
		)
		(pad "45" smd rect
			(at -2.050034 -25.925018 270)
			(size 0.519938 1.4986)
			(layers "F.Cu" "F.Mask" "F.Paste")
			(net "M_C_CPU0_SA_DQS_DN<3>")
		)
		(pad "46" smd rect
			(at -2.050034 -25.07488 270)
			(size 0.519938 1.4986)
			(layers "F.Cu" "F.Mask" "F.Paste")
			(net "GND")
		)
		(pad "47" smd rect
			(at -2.050034 -24.224996 270)
			(size 0.519938 1.4986)
			(layers "F.Cu" "F.Mask" "F.Paste")
			(net "M_C_CPU0_SA_DQ<28>")
		)
		(pad "48" smd rect
			(at -2.050034 -23.375112 270)
			(size 0.519938 1.4986)
			(layers "F.Cu" "F.Mask" "F.Paste")
			(net "GND")
		)
		(pad "49" smd rect
			(at -2.050034 -22.524974 270)
			(size 0.519938 1.4986)
			(layers "F.Cu" "F.Mask" "F.Paste")
			(net "M_C_CPU0_SA_DQ<29>")
		)
		(pad "50" smd rect
			(at -2.050034 -21.67509 270)
			(size 0.519938 1.4986)
			(layers "F.Cu" "F.Mask" "F.Paste")
			(net "GND")
		)
		(pad "51" smd rect
			(at -2.050034 -20.824952 270)
			(size 0.519938 1.4986)
			(layers "F.Cu" "F.Mask" "F.Paste")
			(net "M_C_CPU0_SA_CB<0>")
		)
		(pad "52" smd rect
			(at -2.050034 -19.975068 270)
			(size 0.519938 1.4986)
			(layers "F.Cu" "F.Mask" "F.Paste")
			(net "GND")
		)
		(pad "53" smd rect
			(at -2.050034 -19.12493 270)
			(size 0.519938 1.4986)
			(layers "F.Cu" "F.Mask" "F.Paste")
			(net "M_C_CPU0_SA_CB<1>")
		)
		(pad "54" smd rect
			(at -2.050034 -18.275046 270)
			(size 0.519938 1.4986)
			(layers "F.Cu" "F.Mask" "F.Paste")
			(net "GND")
		)
		(pad "55" smd rect
			(at -2.050034 -17.424908 270)
			(size 0.519938 1.4986)
			(layers "F.Cu" "F.Mask" "F.Paste")
			(net "M_C_CPU0_SA_DQS_DP<4>")
		)
		(pad "56" smd rect
			(at -2.050034 -16.575024 270)
			(size 0.519938 1.4986)
			(layers "F.Cu" "F.Mask" "F.Paste")
			(net "M_C_CPU0_SA_DQS_DN<4>")
		)
		(pad "57" smd rect
			(at -2.050034 -15.724886 270)
			(size 0.519938 1.4986)
			(layers "F.Cu" "F.Mask" "F.Paste")
			(net "GND")
		)
		(pad "58" smd rect
			(at -2.050034 -14.875002 270)
			(size 0.519938 1.4986)
			(layers "F.Cu" "F.Mask" "F.Paste")
			(net "M_C_CPU0_SA_CB<4>")
		)
		(pad "59" smd rect
			(at -2.050034 -14.025118 270)
			(size 0.519938 1.4986)
			(layers "F.Cu" "F.Mask" "F.Paste")
			(net "GND")
		)
		(pad "60" smd rect
			(at -2.050034 -13.17498 270)
			(size 0.519938 1.4986)
			(layers "F.Cu" "F.Mask" "F.Paste")
			(net "M_C_CPU0_SA_CB<5>")
		)
		(pad "61" smd rect
			(at -2.050034 -12.325096 270)
			(size 0.519938 1.4986)
			(layers "F.Cu" "F.Mask" "F.Paste")
			(net "GND")
		)
		(pad "62" smd rect
			(at -2.050034 -11.474958 270)
			(size 0.519938 1.4986)
			(layers "F.Cu" "F.Mask" "F.Paste")
			(net "M_C_CPU0_ALERT_N")
		)
		(pad "63" smd rect
			(at -2.050034 -10.625074 270)
			(size 0.519938 1.4986)
			(layers "F.Cu" "F.Mask" "F.Paste")
			(net "GND")
		)
		(pad "64" smd rect
			(at -2.050034 -9.774936 270)
			(size 0.519938 1.4986)
			(layers "F.Cu" "F.Mask" "F.Paste")
			(net "M_C_CPU0_SA_CS_N<0>")
		)
		(pad "65" smd rect
			(at -2.050034 -8.925052 270)
			(size 0.519938 1.4986)
			(layers "F.Cu" "F.Mask" "F.Paste")
			(net "GND")
		)
		(pad "66" smd rect
			(at -2.050034 -8.074914 270)
			(size 0.519938 1.4986)
			(layers "F.Cu" "F.Mask" "F.Paste")
			(net "M_C_CPU0_SA_CA<0>")
		)
		(pad "67" smd rect
			(at -2.050034 -7.22503 270)
			(size 0.519938 1.4986)
			(layers "F.Cu" "F.Mask" "F.Paste")
			(net "GND")
		)
		(pad "68" smd rect
			(at -2.050034 -6.374892 270)
			(size 0.519938 1.4986)
			(layers "F.Cu" "F.Mask" "F.Paste")
			(net "M_C_CPU0_SA_CA<2>")
		)
		(pad "69" smd rect
			(at -2.050034 -5.525008 270)
			(size 0.519938 1.4986)
			(layers "F.Cu" "F.Mask" "F.Paste")
			(net "GND")
		)
		(pad "70" smd rect
			(at -2.050034 -4.675124 270)
			(size 0.519938 1.4986)
			(layers "F.Cu" "F.Mask" "F.Paste")
			(net "M_C_CPU0_SA_CA<4>")
		)
		(pad "71" smd rect
			(at -2.050034 -3.824986 270)
			(size 0.519938 1.4986)
			(layers "F.Cu" "F.Mask" "F.Paste")
			(net "GND")
		)
		(pad "72" smd rect
			(at -2.050034 -2.975102 270)
			(size 0.519938 1.4986)
			(layers "F.Cu" "F.Mask" "F.Paste")
			(net "M_C_CPU0_SA_CA<6>")
		)
		(pad "73" smd rect
			(at -2.050034 -2.124964 270)
			(size 0.519938 1.4986)
			(layers "F.Cu" "F.Mask" "F.Paste")
			(net "GND")
		)
		(pad "74" smd rect
			(at -2.050034 -1.27508 270)
			(size 0.519938 1.4986)
			(layers "F.Cu" "F.Mask" "F.Paste")
			(net "M_C_CPU0_SA_PAR")
		)
		(pad "75" smd rect
			(at -2.050034 -0.424942 270)
			(size 0.519938 1.4986)
			(layers "F.Cu" "F.Mask" "F.Paste")
			(net "GND")
		)
		(pad "76" smd rect
			(at -2.050034 5.525008 270)
			(size 0.519938 1.4986)
			(layers "F.Cu" "F.Mask" "F.Paste")
			(net "M_C_CPU0_SB_CA<0>")
		)
		(pad "77" smd rect
			(at -2.050034 6.374892 270)
			(size 0.519938 1.4986)
			(layers "F.Cu" "F.Mask" "F.Paste")
			(net "GND")
		)
		(pad "78" smd rect
			(at -2.050034 7.22503 270)
			(size 0.519938 1.4986)
			(layers "F.Cu" "F.Mask" "F.Paste")
			(net "M_C_CPU0_SB_CA<2>")
		)
		(pad "79" smd rect
			(at -2.050034 8.074914 270)
			(size 0.519938 1.4986)
			(layers "F.Cu" "F.Mask" "F.Paste")
			(net "GND")
		)
		(pad "80" smd rect
			(at -2.050034 8.925052 270)
			(size 0.519938 1.4986)
			(layers "F.Cu" "F.Mask" "F.Paste")
			(net "M_C_CPU0_SB_CA<4>")
		)
		(pad "81" smd rect
			(at -2.050034 9.774936 270)
			(size 0.519938 1.4986)
			(layers "F.Cu" "F.Mask" "F.Paste")
			(net "GND")
		)
		(pad "82" smd rect
			(at -2.050034 10.625074 270)
			(size 0.519938 1.4986)
			(layers "F.Cu" "F.Mask" "F.Paste")
			(net "M_C_CPU0_SB_CA<6>")
		)
		(pad "83" smd rect
			(at -2.050034 11.474958 270)
			(size 0.519938 1.4986)
			(layers "F.Cu" "F.Mask" "F.Paste")
			(net "GND")
		)
		(pad "84" smd rect
			(at -2.050034 12.325096 270)
			(size 0.519938 1.4986)
			(layers "F.Cu" "F.Mask" "F.Paste")
			(net "M_C_CPU0_SB_CS_N<0>")
		)
		(pad "85" smd rect
			(at -2.050034 13.17498 270)
			(size 0.519938 1.4986)
			(layers "F.Cu" "F.Mask" "F.Paste")
			(net "GND")
		)
		(pad "86" smd rect
			(at -2.050034 14.025118 270)
			(size 0.519938 1.4986)
			(layers "F.Cu" "F.Mask" "F.Paste")
			(net "M_C_CPU0_SA_RSP<0>")
		)
		(pad "87" smd rect
			(at -2.050034 14.875002 270)
			(size 0.519938 1.4986)
			(layers "F.Cu" "F.Mask" "F.Paste")
			(net "M_C_CPU0_SB_RSP<0>")
		)
		(pad "88" smd rect
			(at -2.050034 15.724886 270)
			(size 0.519938 1.4986)
			(layers "F.Cu" "F.Mask" "F.Paste")
			(net "GND")
		)
		(pad "89" smd rect
			(at -2.050034 16.575024 270)
			(size 0.519938 1.4986)
			(layers "F.Cu" "F.Mask" "F.Paste")
			(net "M_C_CPU0_SB_CB<4>")
		)
		(pad "90" smd rect
			(at -2.050034 17.424908 270)
			(size 0.519938 1.4986)
			(layers "F.Cu" "F.Mask" "F.Paste")
			(net "GND")
		)
		(pad "91" smd rect
			(at -2.050034 18.275046 270)
			(size 0.519938 1.4986)
			(layers "F.Cu" "F.Mask" "F.Paste")
			(net "M_C_CPU0_SB_CB<5>")
		)
		(pad "92" smd rect
			(at -2.050034 19.12493 270)
			(size 0.519938 1.4986)
			(layers "F.Cu" "F.Mask" "F.Paste")
			(net "GND")
		)
		(pad "93" smd rect
			(at -2.050034 19.975068 270)
			(size 0.519938 1.4986)
			(layers "F.Cu" "F.Mask" "F.Paste")
			(net "M_C_CPU0_SB_DQS_DP<9>")
		)
		(pad "94" smd rect
			(at -2.050034 20.824952 270)
			(size 0.519938 1.4986)
			(layers "F.Cu" "F.Mask" "F.Paste")
			(net "M_C_CPU0_SB_DQS_DN<9>")
		)
		(pad "95" smd rect
			(at -2.050034 21.67509 270)
			(size 0.519938 1.4986)
			(layers "F.Cu" "F.Mask" "F.Paste")
			(net "GND")
		)
		(pad "96" smd rect
			(at -2.050034 22.524974 270)
			(size 0.519938 1.4986)
			(layers "F.Cu" "F.Mask" "F.Paste")
			(net "M_C_CPU0_SB_CB<0>")
		)
		(pad "97" smd rect
			(at -2.050034 23.375112 270)
			(size 0.519938 1.4986)
			(layers "F.Cu" "F.Mask" "F.Paste")
			(net "GND")
		)
		(pad "98" smd rect
			(at -2.050034 24.224996 270)
			(size 0.519938 1.4986)
			(layers "F.Cu" "F.Mask" "F.Paste")
			(net "M_C_CPU0_SB_CB<1>")
		)
		(pad "99" smd rect
			(at -2.050034 25.07488 270)
			(size 0.519938 1.4986)
			(layers "F.Cu" "F.Mask" "F.Paste")
			(net "GND")
		)
		(pad "100" smd rect
			(at -2.050034 25.925018 270)
			(size 0.519938 1.4986)
			(layers "F.Cu" "F.Mask" "F.Paste")
			(net "M_C_CPU0_SB_DQ<0>")
		)
		(pad "101" smd rect
			(at -2.050034 26.774902 270)
			(size 0.519938 1.4986)
			(layers "F.Cu" "F.Mask" "F.Paste")
			(net "GND")
		)
		(pad "102" smd rect
			(at -2.050034 27.62504 270)
			(size 0.519938 1.4986)
			(layers "F.Cu" "F.Mask" "F.Paste")
			(net "M_C_CPU0_SB_DQ<1>")
		)
		(pad "103" smd rect
			(at -2.050034 28.474924 270)
			(size 0.519938 1.4986)
			(layers "F.Cu" "F.Mask" "F.Paste")
			(net "GND")
		)
		(pad "104" smd rect
			(at -2.050034 29.325062 270)
			(size 0.519938 1.4986)
			(layers "F.Cu" "F.Mask" "F.Paste")
			(net "M_C_CPU0_SB_DQS_DP<0>")
		)
		(pad "105" smd rect
			(at -2.050034 30.174946 270)
			(size 0.519938 1.4986)
			(layers "F.Cu" "F.Mask" "F.Paste")
			(net "M_C_CPU0_SB_DQS_DN<0>")
		)
		(pad "106" smd rect
			(at -2.050034 31.025084 270)
			(size 0.519938 1.4986)
			(layers "F.Cu" "F.Mask" "F.Paste")
			(net "GND")
		)
		(pad "107" smd rect
			(at -2.050034 31.874968 270)
			(size 0.519938 1.4986)
			(layers "F.Cu" "F.Mask" "F.Paste")
			(net "M_C_CPU0_SB_DQ<4>")
		)
		(pad "108" smd rect
			(at -2.050034 32.725106 270)
			(size 0.519938 1.4986)
			(layers "F.Cu" "F.Mask" "F.Paste")
			(net "GND")
		)
		(pad "109" smd rect
			(at -2.050034 33.57499 270)
			(size 0.519938 1.4986)
			(layers "F.Cu" "F.Mask" "F.Paste")
			(net "M_C_CPU0_SB_DQ<5>")
		)
		(pad "110" smd rect
			(at -2.050034 34.425128 270)
			(size 0.519938 1.4986)
			(layers "F.Cu" "F.Mask" "F.Paste")
			(net "GND")
		)
		(pad "111" smd rect
			(at -2.050034 35.275012 270)
			(size 0.519938 1.4986)
			(layers "F.Cu" "F.Mask" "F.Paste")
			(net "M_C_CPU0_SB_DQ<8>")
		)
		(pad "112" smd rect
			(at -2.050034 36.124896 270)
			(size 0.519938 1.4986)
			(layers "F.Cu" "F.Mask" "F.Paste")
			(net "GND")
		)
	)
)
